(kicad_pcb
	(version 20260206)
	(generator "pcbnew")
	(generator_version "10.0")
	(general
		(thickness 1.6)
		(legacy_teardrops no)
	)
	(paper "A4")
	(title_block
		(title "01162023_DA0F0TEBIF0_F0T_Expander_BD_F_brd_V02_OCP.brd")
		(comment 1 "Grand Teton / footprints 8544-8551 of 9728")
	)
	(layers
		(0 "F.Cu" signal "TOP")
		(4 "In1.Cu" signal "GND")
		(6 "In2.Cu" signal "VCC")
		(8 "In3.Cu" signal "VCC1")
		(10 "In4.Cu" signal "GND1")
		(12 "In5.Cu" signal "IN1")
		(14 "In6.Cu" signal "GND2")
		(16 "In7.Cu" signal "IN2")
		(18 "In8.Cu" signal "GND3")
		(20 "In9.Cu" signal "IN3")
		(22 "In10.Cu" signal "GND4")
		(24 "In11.Cu" signal "IN4")
		(26 "In12.Cu" signal "GND5")
		(28 "In13.Cu" signal "IN5")
		(30 "In14.Cu" signal "GND6")
		(32 "In15.Cu" signal "IN6")
		(34 "In16.Cu" signal "GND7")
		(2 "B.Cu" signal "BOTTOM")
		(9 "F.Adhes" user "F.Adhesive")
		(11 "B.Adhes" user "B.Adhesive")
		(13 "F.Paste" user "Package Geometry/Pastemask Top")
		(15 "B.Paste" user "Package Geometry/Pastemask Bottom")
		(5 "F.SilkS" user "Ref Des/Silkscreen Top")
		(7 "B.SilkS" user "Ref Des/Silkscreen Bottom")
		(1 "F.Mask" user "Board Geometry/Soldermask Top")
		(3 "B.Mask" user "Board Geometry/Soldermask Bottom")
		(17 "Dwgs.User" user "User.Drawings")
		(19 "Cmts.User" user "User.Comments")
		(21 "Eco1.User" user "User.Eco1")
		(23 "Eco2.User" user "User.Eco2")
		(25 "Edge.Cuts" user "Board Geometry/Outline")
		(27 "Margin" user)
		(31 "F.CrtYd" user "Package Geometry/Place Bound Top")
		(29 "B.CrtYd" user "Package Geometry/Place Bound Bottom")
		(35 "F.Fab" user "Ref Des/Assembly Top")
		(33 "B.Fab" user "Ref Des/Assembly Bottom")
	)
	(footprint ""
		(layer "B.Cu")
		(at 345.29395 -218.787218 -90)
		(property "Reference" "C2047"
			(at 0 0 90)
			(layer "B.SilkS")
			(hide yes)
			(effects
				(font
					(size 1.27 1.27)
				)
				(justify mirror)
			)
		)
		(property "Value" ""
			(at 0 0 90)
			(layer "B.Fab")
			(effects
				(font
					(size 1.27 1.27)
				)
				(justify mirror)
			)
		)
		(duplicate_pad_numbers_are_jumpers no)
		(fp_line
			(start -0.69215 0.2921)
			(end 0.69215 0.2921)
			(stroke
				(width 0.1524)
				(type default)
			)
			(layer "B.SilkS")
		)
		(fp_line
			(start 0.69215 0.2921)
			(end 0.69215 -0.2921)
			(stroke
				(width 0.1524)
				(type default)
			)
			(layer "B.SilkS")
		)
		(fp_line
			(start -0.69215 -0.2921)
			(end -0.69215 0.2921)
			(stroke
				(width 0.1524)
				(type default)
			)
			(layer "B.SilkS")
		)
		(fp_line
			(start 0.69215 -0.2921)
			(end -0.69215 -0.2921)
			(stroke
				(width 0.1524)
				(type default)
			)
			(layer "B.SilkS")
		)
		(fp_line
			(start -0.51435 0.2794)
			(end 0.51435 0.2794)
			(stroke
				(width 0.1)
				(type default)
			)
			(layer "B.Fab")
		)
		(fp_line
			(start 0.51435 0.2794)
			(end 0.51435 -0.2794)
			(stroke
				(width 0.1)
				(type default)
			)
			(layer "B.Fab")
		)
		(fp_line
			(start -0.51435 -0.2794)
			(end -0.51435 0.2794)
			(stroke
				(width 0.1)
				(type default)
			)
			(layer "B.Fab")
		)
		(fp_line
			(start 0.51435 -0.2794)
			(end -0.51435 -0.2794)
			(stroke
				(width 0.1)
				(type default)
			)
			(layer "B.Fab")
		)
		(pad "1" smd circle
			(at 0.40005 0 90)
			(size 0 0)
			(layers "B.Cu" "B.Mask" "B.Paste")
			(net "P3V3_FPGA_VCCIO1")
		)
		(pad "2" smd circle
			(at -0.40005 0 90)
			(size 0 0)
			(layers "B.Cu" "B.Mask" "B.Paste")
			(net "GND")
		)
		(zone
			(layer "B.Cu")
			(hatch none 0.5)
			(connect_pads
				(clearance 0)
			)
			(min_thickness 0.25)
			(keepout
				(tracks not_allowed)
				(vias allowed)
				(pads allowed)
				(copperpour not_allowed)
				(footprints allowed)
			)
			(placement
				(enabled no)
				(sheetname "")
			)
			(fill
				(thermal_gap 0.5)
				(thermal_bridge_width 0.5)
				(island_removal_mode 0)
			)
			(polygon
				(pts
					(xy 345.20632 -218.596718) (xy 345.148154 -218.688158) (xy 345.148154 -218.887548) (xy 345.20632 -218.977718)
					(xy 345.38158 -218.977718) (xy 345.44 -218.887548) (xy 345.44 -218.688158) (xy 345.381834 -218.596718)
				)
			)
		)
	)
	(footprint ""
		(layer "B.Cu")
		(at 227.067618 -219.10421 180)
		(property "Reference" "C2018"
			(at 0 0 0)
			(layer "B.SilkS")
			(hide yes)
			(effects
				(font
					(size 1.27 1.27)
				)
				(justify mirror)
			)
		)
		(property "Value" ""
			(at 0 0 0)
			(layer "B.Fab")
			(effects
				(font
					(size 1.27 1.27)
				)
				(justify mirror)
			)
		)
		(duplicate_pad_numbers_are_jumpers no)
		(fp_line
			(start 0.69215 0.2921)
			(end 0.69215 -0.2921)
			(stroke
				(width 0.1524)
				(type default)
			)
			(layer "B.SilkS")
		)
		(fp_line
			(start 0.69215 -0.2921)
			(end -0.69215 -0.2921)
			(stroke
				(width 0.1524)
				(type default)
			)
			(layer "B.SilkS")
		)
		(fp_line
			(start -0.69215 0.2921)
			(end 0.69215 0.2921)
			(stroke
				(width 0.1524)
				(type default)
			)
			(layer "B.SilkS")
		)
		(fp_line
			(start -0.69215 -0.2921)
			(end -0.69215 0.2921)
			(stroke
				(width 0.1524)
				(type default)
			)
			(layer "B.SilkS")
		)
		(fp_line
			(start 0.51435 0.2794)
			(end 0.51435 -0.2794)
			(stroke
				(width 0.1)
				(type default)
			)
			(layer "B.Fab")
		)
		(fp_line
			(start 0.51435 -0.2794)
			(end -0.51435 -0.2794)
			(stroke
				(width 0.1)
				(type default)
			)
			(layer "B.Fab")
		)
		(fp_line
			(start -0.51435 0.2794)
			(end 0.51435 0.2794)
			(stroke
				(width 0.1)
				(type default)
			)
			(layer "B.Fab")
		)
		(fp_line
			(start -0.51435 -0.2794)
			(end -0.51435 0.2794)
			(stroke
				(width 0.1)
				(type default)
			)
			(layer "B.Fab")
		)
		(pad "1" smd circle
			(at 0.40005 0)
			(size 0 0)
			(layers "B.Cu" "B.Mask" "B.Paste")
			(net "P1V2_AUX")
		)
		(pad "2" smd circle
			(at -0.40005 0)
			(size 0 0)
			(layers "B.Cu" "B.Mask" "B.Paste")
			(net "GND")
		)
		(zone
			(layer "B.Cu")
			(hatch none 0.5)
			(connect_pads
				(clearance 0)
			)
			(min_thickness 0.25)
			(keepout
				(tracks not_allowed)
				(vias allowed)
				(pads allowed)
				(copperpour not_allowed)
				(footprints allowed)
			)
			(placement
				(enabled no)
				(sheetname "")
			)
			(fill
				(thermal_gap 0.5)
				(thermal_bridge_width 0.5)
				(island_removal_mode 0)
			)
			(polygon
				(pts
					(xy 226.877118 -219.19184) (xy 226.968558 -219.250006) (xy 227.167948 -219.250006) (xy 227.258118 -219.19184)
					(xy 227.258118 -219.01658) (xy 227.167948 -218.95816) (xy 226.968558 -218.95816) (xy 226.877118 -219.016326)
				)
			)
		)
	)
	(footprint ""
		(layer "B.Cu")
		(at 130.336544 -303.649634 -90)
		(property "Reference" "PR10"
			(at 0 0 90)
			(layer "B.SilkS")
			(hide yes)
			(effects
				(font
					(size 1.27 1.27)
				)
				(justify mirror)
			)
		)
		(property "Value" ""
			(at 0 0 90)
			(layer "B.Fab")
			(effects
				(font
					(size 1.27 1.27)
				)
				(justify mirror)
			)
		)
		(duplicate_pad_numbers_are_jumpers no)
		(fp_line
			(start -1.2954 0.5842)
			(end 1.2954 0.5842)
			(stroke
				(width 0.1524)
				(type default)
			)
			(layer "B.SilkS")
		)
		(fp_line
			(start 1.2954 0.5842)
			(end 1.2954 -0.5842)
			(stroke
				(width 0.1524)
				(type default)
			)
			(layer "B.SilkS")
		)
		(fp_line
			(start -1.2954 -0.5842)
			(end -1.2954 0.5842)
			(stroke
				(width 0.1524)
				(type default)
			)
			(layer "B.SilkS")
		)
		(fp_line
			(start 1.2954 -0.5842)
			(end -1.2954 -0.5842)
			(stroke
				(width 0.1524)
				(type default)
			)
			(layer "B.SilkS")
		)
		(fp_line
			(start -0.8636 0.4572)
			(end 0.8636 0.4572)
			(stroke
				(width 0.1)
				(type default)
			)
			(layer "B.Fab")
		)
		(fp_line
			(start 0.8636 0.4572)
			(end 0.8636 0.4318)
			(stroke
				(width 0.1)
				(type default)
			)
			(layer "B.Fab")
		)
		(fp_line
			(start 0.8636 0.4318)
			(end 0.8636 0.4064)
			(stroke
				(width 0.1)
				(type default)
			)
			(layer "B.Fab")
		)
		(fp_line
			(start -1.1938 0.4064)
			(end -0.8636 0.4064)
			(stroke
				(width 0.1)
				(type default)
			)
			(layer "B.Fab")
		)
		(fp_line
			(start -0.8636 0.4064)
			(end -0.8636 0.4572)
			(stroke
				(width 0.1)
				(type default)
			)
			(layer "B.Fab")
		)
		(fp_line
			(start 0.8636 0.4064)
			(end 1.1938 0.4064)
			(stroke
				(width 0.1)
				(type default)
			)
			(layer "B.Fab")
		)
		(fp_line
			(start 1.1938 0.4064)
			(end 1.1938 -0.406654)
			(stroke
				(width 0.1)
				(type default)
			)
			(layer "B.Fab")
		)
		(fp_line
			(start -1.1938 -0.406654)
			(end -1.1938 0.4064)
			(stroke
				(width 0.1)
				(type default)
			)
			(layer "B.Fab")
		)
		(fp_line
			(start -0.8636 -0.406654)
			(end -1.1938 -0.406654)
			(stroke
				(width 0.1)
				(type default)
			)
			(layer "B.Fab")
		)
		(fp_line
			(start 0.8636 -0.406654)
			(end 0.8636 -0.4572)
			(stroke
				(width 0.1)
				(type default)
			)
			(layer "B.Fab")
		)
		(fp_line
			(start 1.1938 -0.406654)
			(end 0.8636 -0.406654)
			(stroke
				(width 0.1)
				(type default)
			)
			(layer "B.Fab")
		)
		(fp_line
			(start -0.8636 -0.4572)
			(end -0.8636 -0.406654)
			(stroke
				(width 0.1)
				(type default)
			)
			(layer "B.Fab")
		)
		(fp_line
			(start 0.8636 -0.4572)
			(end -0.8636 -0.4572)
			(stroke
				(width 0.1)
				(type default)
			)
			(layer "B.Fab")
		)
		(pad "1" smd rect
			(at 0.7366 0 180)
			(size 0.7112 0.8128)
			(layers "B.Cu" "B.Mask" "B.Paste")
			(net "P0V8_PEX1")
		)
		(pad "2" smd rect
			(at -0.7366 0 180)
			(size 0.7112 0.8128)
			(layers "B.Cu" "B.Mask" "B.Paste")
			(net "GND")
		)
	)
	(footprint ""
		(layer "B.Cu")
		(at 413.201358 -305.399948 -90)
		(property "Reference" "C3477"
			(at 0 0 90)
			(layer "B.SilkS")
			(hide yes)
			(effects
				(font
					(size 1.27 1.27)
				)
				(justify mirror)
			)
		)
		(property "Value" ""
			(at 0 0 90)
			(layer "B.Fab")
			(effects
				(font
					(size 1.27 1.27)
				)
				(justify mirror)
			)
		)
		(duplicate_pad_numbers_are_jumpers no)
		(fp_line
			(start -0.299974 0.150114)
			(end 0.299974 0.150114)
			(stroke
				(width 0.1)
				(type default)
			)
			(layer "B.Fab")
		)
		(fp_line
			(start 0.299974 0.150114)
			(end 0.299974 -0.150114)
			(stroke
				(width 0.1)
				(type default)
			)
			(layer "B.Fab")
		)
		(fp_line
			(start -0.299974 -0.150114)
			(end -0.299974 0.150114)
			(stroke
				(width 0.1)
				(type default)
			)
			(layer "B.Fab")
		)
		(fp_line
			(start 0.299974 -0.150114)
			(end -0.299974 -0.150114)
			(stroke
				(width 0.1)
				(type default)
			)
			(layer "B.Fab")
		)
		(pad "1" smd rect
			(at 0.2667 0 90)
			(size 0.3048 0.381)
			(layers "B.Cu" "B.Mask" "B.Paste")
			(net "P1V25_SERDES_VDDPLL_PEX3")
		)
		(pad "2" smd rect
			(at -0.2667 0 90)
			(size 0.3048 0.381)
			(layers "B.Cu" "B.Mask" "B.Paste")
			(net "GND")
		)
	)
	(footprint ""
		(layer "B.Cu")
		(at 130.893058 -229.997)
		(property "Reference" "R3463"
			(at 0 0 0)
			(layer "B.SilkS")
			(hide yes)
			(effects
				(font
					(size 1.27 1.27)
				)
				(justify mirror)
			)
		)
		(property "Value" ""
			(at 0 0 0)
			(layer "B.Fab")
			(effects
				(font
					(size 1.27 1.27)
				)
				(justify mirror)
			)
		)
		(duplicate_pad_numbers_are_jumpers no)
		(fp_line
			(start -0.7874 -0.4064)
			(end -0.7874 0.4064)
			(stroke
				(width 0.1524)
				(type default)
			)
			(layer "B.SilkS")
		)
		(fp_line
			(start -0.7874 0.4064)
			(end 0.7874 0.4064)
			(stroke
				(width 0.1524)
				(type default)
			)
			(layer "B.SilkS")
		)
		(fp_line
			(start 0.7874 -0.4064)
			(end -0.7874 -0.4064)
			(stroke
				(width 0.1524)
				(type default)
			)
			(layer "B.SilkS")
		)
		(fp_line
			(start 0.7874 0.4064)
			(end 0.7874 -0.4064)
			(stroke
				(width 0.1524)
				(type default)
			)
			(layer "B.SilkS")
		)
		(fp_line
			(start -0.67945 -0.3048)
			(end -0.67945 0.3048)
			(stroke
				(width 0.1)
				(type default)
			)
			(layer "B.Fab")
		)
		(fp_line
			(start -0.67945 0.3048)
			(end -0.120396 0.3048)
			(stroke
				(width 0.1)
				(type default)
			)
			(layer "B.Fab")
		)
		(fp_line
			(start -0.12065 -0.3048)
			(end -0.67945 -0.3048)
			(stroke
				(width 0.1)
				(type default)
			)
			(layer "B.Fab")
		)
		(fp_line
			(start -0.12065 -0.2794)
			(end -0.12065 -0.3048)
			(stroke
				(width 0.1)
				(type default)
			)
			(layer "B.Fab")
		)
		(fp_line
			(start -0.120396 0.2794)
			(end 0.12065 0.2794)
			(stroke
				(width 0.1)
				(type default)
			)
			(layer "B.Fab")
		)
		(fp_line
			(start -0.120396 0.3048)
			(end -0.120396 0.2794)
			(stroke
				(width 0.1)
				(type default)
			)
			(layer "B.Fab")
		)
		(fp_line
			(start 0.12065 -0.305054)
			(end 0.12065 -0.2794)
			(stroke
				(width 0.1)
				(type default)
			)
			(layer "B.Fab")
		)
		(fp_line
			(start 0.12065 -0.2794)
			(end -0.12065 -0.2794)
			(stroke
				(width 0.1)
				(type default)
			)
			(layer "B.Fab")
		)
		(fp_line
			(start 0.12065 0.2794)
			(end 0.12065 0.3048)
			(stroke
				(width 0.1)
				(type default)
			)
			(layer "B.Fab")
		)
		(fp_line
			(start 0.12065 0.3048)
			(end 0.67945 0.3048)
			(stroke
				(width 0.1)
				(type default)
			)
			(layer "B.Fab")
		)
		(fp_line
			(start 0.67945 -0.305054)
			(end 0.12065 -0.305054)
			(stroke
				(width 0.1)
				(type default)
			)
			(layer "B.Fab")
		)
		(fp_line
			(start 0.67945 0.3048)
			(end 0.67945 -0.305054)
			(stroke
				(width 0.1)
				(type default)
			)
			(layer "B.Fab")
		)
		(pad "1" smd circle
			(at 0.40005 0 180)
			(size 0 0)
			(layers "B.Cu" "B.Mask" "B.Paste")
			(net "SPI_PEX1_SDIO2_R")
		)
		(pad "2" smd circle
			(at -0.40005 0 180)
			(size 0 0)
			(layers "B.Cu" "B.Mask" "B.Paste")
			(net "SPI_PEX1_SDIO2_R1")
		)
	)
	(footprint ""
		(layer "B.Cu")
		(at 214.031576 -369.356386)
		(property "Reference" "PR26"
			(at 0 0 0)
			(layer "B.SilkS")
			(hide yes)
			(effects
				(font
					(size 1.27 1.27)
				)
				(justify mirror)
			)
		)
		(property "Value" ""
			(at 0 0 0)
			(layer "B.Fab")
			(effects
				(font
					(size 1.27 1.27)
				)
				(justify mirror)
			)
		)
		(duplicate_pad_numbers_are_jumpers no)
		(fp_line
			(start -0.7874 -0.4064)
			(end -0.7874 0.4064)
			(stroke
				(width 0.1524)
				(type default)
			)
			(layer "B.SilkS")
		)
		(fp_line
			(start -0.7874 0.4064)
			(end 0.7874 0.4064)
			(stroke
				(width 0.1524)
				(type default)
			)
			(layer "B.SilkS")
		)
		(fp_line
			(start 0.7874 -0.4064)
			(end -0.7874 -0.4064)
			(stroke
				(width 0.1524)
				(type default)
			)
			(layer "B.SilkS")
		)
		(fp_line
			(start 0.7874 0.4064)
			(end 0.7874 -0.4064)
			(stroke
				(width 0.1524)
				(type default)
			)
			(layer "B.SilkS")
		)
		(fp_line
			(start -0.67945 -0.3048)
			(end -0.67945 0.3048)
			(stroke
				(width 0.1)
				(type default)
			)
			(layer "B.Fab")
		)
		(fp_line
			(start -0.67945 0.3048)
			(end -0.120396 0.3048)
			(stroke
				(width 0.1)
				(type default)
			)
			(layer "B.Fab")
		)
		(fp_line
			(start -0.12065 -0.3048)
			(end -0.67945 -0.3048)
			(stroke
				(width 0.1)
				(type default)
			)
			(layer "B.Fab")
		)
		(fp_line
			(start -0.12065 -0.2794)
			(end -0.12065 -0.3048)
			(stroke
				(width 0.1)
				(type default)
			)
			(layer "B.Fab")
		)
		(fp_line
			(start -0.120396 0.2794)
			(end 0.12065 0.2794)
			(stroke
				(width 0.1)
				(type default)
			)
			(layer "B.Fab")
		)
		(fp_line
			(start -0.120396 0.3048)
			(end -0.120396 0.2794)
			(stroke
				(width 0.1)
				(type default)
			)
			(layer "B.Fab")
		)
		(fp_line
			(start 0.12065 -0.305054)
			(end 0.12065 -0.2794)
			(stroke
				(width 0.1)
				(type default)
			)
			(layer "B.Fab")
		)
		(fp_line
			(start 0.12065 -0.2794)
			(end -0.12065 -0.2794)
			(stroke
				(width 0.1)
				(type default)
			)
			(layer "B.Fab")
		)
		(fp_line
			(start 0.12065 0.2794)
			(end 0.12065 0.3048)
			(stroke
				(width 0.1)
				(type default)
			)
			(layer "B.Fab")
		)
		(fp_line
			(start 0.12065 0.3048)
			(end 0.67945 0.3048)
			(stroke
				(width 0.1)
				(type default)
			)
			(layer "B.Fab")
		)
		(fp_line
			(start 0.67945 -0.305054)
			(end 0.12065 -0.305054)
			(stroke
				(width 0.1)
				(type default)
			)
			(layer "B.Fab")
		)
		(fp_line
			(start 0.67945 0.3048)
			(end 0.67945 -0.305054)
			(stroke
				(width 0.1)
				(type default)
			)
			(layer "B.Fab")
		)
		(pad "1" smd circle
			(at 0.40005 0 180)
			(size 0 0)
			(layers "B.Cu" "B.Mask" "B.Paste")
			(net "HSC_VDD_1")
		)
		(pad "2" smd circle
			(at -0.40005 0 180)
			(size 0 0)
			(layers "B.Cu" "B.Mask" "B.Paste")
			(net "HSC_VDD")
		)
	)
	(footprint ""
		(layer "B.Cu")
		(at 56.325008 -293.99992 90)
		(property "Reference" "C1156"
			(at 0 0 90)
			(layer "B.SilkS")
			(hide yes)
			(effects
				(font
					(size 1.27 1.27)
				)
				(justify mirror)
			)
		)
		(property "Value" ""
			(at 0 0 90)
			(layer "B.Fab")
			(effects
				(font
					(size 1.27 1.27)
				)
				(justify mirror)
			)
		)
		(duplicate_pad_numbers_are_jumpers no)
		(fp_line
			(start 0.299974 -0.150114)
			(end -0.299974 -0.150114)
			(stroke
				(width 0.1)
				(type default)
			)
			(layer "B.Fab")
		)
		(fp_line
			(start -0.299974 -0.150114)
			(end -0.299974 0.150114)
			(stroke
				(width 0.1)
				(type default)
			)
			(layer "B.Fab")
		)
		(fp_line
			(start 0.299974 0.150114)
			(end 0.299974 -0.150114)
			(stroke
				(width 0.1)
				(type default)
			)
			(layer "B.Fab")
		)
		(fp_line
			(start -0.299974 0.150114)
			(end 0.299974 0.150114)
			(stroke
				(width 0.1)
				(type default)
			)
			(layer "B.Fab")
		)
		(pad "1" smd rect
			(at 0.2667 0 270)
			(size 0.3048 0.381)
			(layers "B.Cu" "B.Mask" "B.Paste")
			(net "P0V8_PEX0")
		)
		(pad "2" smd rect
			(at -0.2667 0 270)
			(size 0.3048 0.381)
			(layers "B.Cu" "B.Mask" "B.Paste")
			(net "GND")
		)
	)
	(footprint ""
		(layer "B.Cu")
		(at 331.332332 -218.208352)
		(property "Reference" "C2082"
			(at 0 0 0)
			(layer "B.SilkS")
			(hide yes)
			(effects
				(font
					(size 1.27 1.27)
				)
				(justify mirror)
			)
		)
		(property "Value" ""
			(at 0 0 0)
			(layer "B.Fab")
			(effects
				(font
					(size 1.27 1.27)
				)
				(justify mirror)
			)
		)
		(duplicate_pad_numbers_are_jumpers no)
		(fp_line
			(start -0.69215 -0.2921)
			(end -0.69215 0.2921)
			(stroke
				(width 0.1524)
				(type default)
			)
			(layer "B.SilkS")
		)
		(fp_line
			(start -0.69215 0.2921)
			(end 0.69215 0.2921)
			(stroke
				(width 0.1524)
				(type default)
			)
			(layer "B.SilkS")
		)
		(fp_line
			(start 0.69215 -0.2921)
			(end -0.69215 -0.2921)
			(stroke
				(width 0.1524)
				(type default)
			)
			(layer "B.SilkS")
		)
		(fp_line
			(start 0.69215 0.2921)
			(end 0.69215 -0.2921)
			(stroke
				(width 0.1524)
				(type default)
			)
			(layer "B.SilkS")
		)
		(fp_line
			(start -0.51435 -0.2794)
			(end -0.51435 0.2794)
			(stroke
				(width 0.1)
				(type default)
			)
			(layer "B.Fab")
		)
		(fp_line
			(start -0.51435 0.2794)
			(end 0.51435 0.2794)
			(stroke
				(width 0.1)
				(type default)
			)
			(layer "B.Fab")
		)
		(fp_line
			(start 0.51435 -0.2794)
			(end -0.51435 -0.2794)
			(stroke
				(width 0.1)
				(type default)
			)
			(layer "B.Fab")
		)
		(fp_line
			(start 0.51435 0.2794)
			(end 0.51435 -0.2794)
			(stroke
				(width 0.1)
				(type default)
			)
			(layer "B.Fab")
		)
		(pad "1" smd circle
			(at 0.40005 0 180)
			(size 0 0)
			(layers "B.Cu" "B.Mask" "B.Paste")
			(net "P3V3_FPGA_VCCIO4")
		)
		(pad "2" smd circle
			(at -0.40005 0 180)
			(size 0 0)
			(layers "B.Cu" "B.Mask" "B.Paste")
			(net "GND")
		)
		(zone
			(layer "B.Cu")
			(hatch none 0.5)
			(connect_pads
				(clearance 0)
			)
			(min_thickness 0.25)
			(keepout
				(tracks not_allowed)
				(vias allowed)
				(pads allowed)
				(copperpour not_allowed)
				(footprints allowed)
			)
			(placement
				(enabled no)
				(sheetname "")
			)
			(fill
				(thermal_gap 0.5)
				(thermal_bridge_width 0.5)
				(island_removal_mode 0)
			)
			(polygon
				(pts
					(xy 331.522832 -218.120722) (xy 331.431392 -218.062556) (xy 331.232002 -218.062556) (xy 331.141832 -218.120722)
					(xy 331.141832 -218.295982) (xy 331.232002 -218.354402) (xy 331.431392 -218.354402) (xy 331.522832 -218.296236)
				)
			)
		)
	)
)
